# BASEBOARD_FAB2 (Tioga Pass) — schematic netlist excerpt (pin names and nets, part order shuffled) for the footprints in the layout excerpt that follows; sources: Cadence DE-HDL packaged netlist, KiCad conversion of Wiwynn_Tioga_Pass_MB.brd

C1R16  CAP  10UF 6.3V 20% X6S  pkg 0603  page 139 : A = P0V9_LAN ; B = GND
R2T71  RES  0.0 5% EMPTY  pkg 0402  page 93 : A = FM_CPU0_PROCHOT_LVT3_K_N ; B = H_CPU0_PROCHOT_G_PCH_N
C3P30  CAP  0.22UF 16V 10% X7R  pkg 0402  page 107 : A = P3E_CPU0_PE1_SS_TXP<5> ; B = P3E_CPU0_PE1_PCH_TXP<5>

(kicad_pcb
	(version 20260206)
	(generator "pcbnew")
	(generator_version "10.0")
	(general
		(thickness 1.6)
		(legacy_teardrops no)
	)
	(paper "A4")
	(title_block
		(title "Wiwynn_Tioga_Pass_MB.brd")
		(comment 1 "Tioga Pass / footprints 3528-3530 of 4770")
	)
	(layers
		(0 "F.Cu" signal "TOP")
		(4 "In1.Cu" signal "L2GND")
		(6 "In2.Cu" signal "L3")
		(8 "In3.Cu" signal "L4GND")
		(10 "In4.Cu" signal "L5")
		(12 "In5.Cu" signal "L6GND")
		(14 "In6.Cu" signal "L7VCC")
		(16 "In7.Cu" signal "L8VCC")
		(18 "In8.Cu" signal "L9GND")
		(20 "In9.Cu" signal "L10")
		(22 "In10.Cu" signal "L11GND")
		(24 "In11.Cu" signal "L12")
		(26 "In12.Cu" signal "L13GND")
		(2 "B.Cu" signal "BOTTOM")
		(9 "F.Adhes" user "F.Adhesive")
		(11 "B.Adhes" user "B.Adhesive")
		(13 "F.Paste" user "Package Geometry/Pastemask Top")
		(15 "B.Paste" user "Package Geometry/Pastemask Bottom")
		(5 "F.SilkS" user "Ref Des/Silkscreen Top")
		(7 "B.SilkS" user "Ref Des/Silkscreen Bottom")
		(1 "F.Mask" user "Board Geometry/Soldermask Top")
		(3 "B.Mask" user "Board Geometry/Soldermask Bottom")
		(17 "Dwgs.User" user "User.Drawings")
		(19 "Cmts.User" user "User.Comments")
		(21 "Eco1.User" user "User.Eco1")
		(23 "Eco2.User" user "User.Eco2")
		(25 "Edge.Cuts" user "Board Geometry/Outline")
		(27 "Margin" user)
		(31 "F.CrtYd" user "Package Geometry/Place Bound Top")
		(29 "B.CrtYd" user "Package Geometry/Place Bound Bottom")
		(35 "F.Fab" user "Ref Des/Assembly Top")
		(33 "B.Fab" user "Ref Des/Assembly Bottom")
	)
	(footprint ""
		(layer "B.Cu")
		(at 488.191302 -45.584872 -90)
		(property "Reference" "C1R16"
			(at 0 0 90)
			(layer "B.SilkS")
			(hide yes)
			(effects
				(font
					(size 1.27 1.27)
				)
				(justify mirror)
			)
		)
		(property "Value" ""
			(at 0 0 90)
			(layer "B.Fab")
			(effects
				(font
					(size 1.27 1.27)
				)
				(justify mirror)
			)
		)
		(duplicate_pad_numbers_are_jumpers no)
		(fp_poly
			(pts
				(xy 0.4953 -0.2032) (xy -0.4953 -0.2032) (xy -0.4953 1.6002) (xy 0.4953 1.6002)
			)
			(stroke
				(width 0)
				(type default)
			)
			(fill no)
			(layer "B.CrtYd")
		)
		(fp_line
			(start -0.4953 1.6002)
			(end 0.4953 1.6002)
			(stroke
				(width 0.1)
				(type default)
			)
			(layer "B.Fab")
		)
		(fp_line
			(start 0.4953 1.6002)
			(end 0.4953 -0.2032)
			(stroke
				(width 0.1)
				(type default)
			)
			(layer "B.Fab")
		)
		(fp_line
			(start -0.4953 -0.2032)
			(end -0.4953 1.6002)
			(stroke
				(width 0.1)
				(type default)
			)
			(layer "B.Fab")
		)
		(fp_line
			(start 0.4953 -0.2032)
			(end -0.4953 -0.2032)
			(stroke
				(width 0.1)
				(type default)
			)
			(layer "B.Fab")
		)
		(pad "1" smd rect
			(at 0 0 90)
			(size 0.762 0.889)
			(layers "B.Cu" "B.Mask" "B.Paste")
			(net "P0V9_LAN")
		)
		(pad "2" smd rect
			(at 0 1.397 90)
			(size 0.762 0.889)
			(layers "B.Cu" "B.Mask" "B.Paste")
			(net "GND")
		)
		(zone
			(layer "B.Cu")
			(hatch none 0.5)
			(connect_pads
				(clearance 0)
			)
			(min_thickness 0.25)
			(keepout
				(tracks not_allowed)
				(vias allowed)
				(pads allowed)
				(copperpour not_allowed)
				(footprints allowed)
			)
			(placement
				(enabled no)
				(sheetname "")
			)
			(fill
				(thermal_gap 0.5)
				(thermal_bridge_width 0.5)
				(island_removal_mode 0)
			)
			(polygon
				(pts
					(xy 487.746802 -45.203872) (xy 487.746802 -45.965872) (xy 487.238802 -45.965872) (xy 487.238802 -45.203872)
				)
			)
		)
	)
	(footprint ""
		(layer "B.Cu")
		(at 361.444794 -45.607986 -90)
		(property "Reference" "R2T71"
			(at 0 0 90)
			(layer "B.SilkS")
			(hide yes)
			(effects
				(font
					(size 1.27 1.27)
				)
				(justify mirror)
			)
		)
		(property "Value" ""
			(at 0 0 90)
			(layer "B.Fab")
			(effects
				(font
					(size 1.27 1.27)
				)
				(justify mirror)
			)
		)
		(duplicate_pad_numbers_are_jumpers no)
		(fp_poly
			(pts
				(xy 0.2794 -0.1016) (xy -0.2794 -0.1016) (xy -0.2794 0.9906) (xy 0.2794 0.9906)
			)
			(stroke
				(width 0)
				(type default)
			)
			(fill no)
			(layer "B.CrtYd")
		)
		(fp_line
			(start -0.2794 0.9906)
			(end -0.2794 -0.1016)
			(stroke
				(width 0.1)
				(type default)
			)
			(layer "B.Fab")
		)
		(fp_line
			(start 0.2794 0.9906)
			(end -0.2794 0.9906)
			(stroke
				(width 0.1)
				(type default)
			)
			(layer "B.Fab")
		)
		(fp_line
			(start -0.2794 -0.1016)
			(end 0.2794 -0.1016)
			(stroke
				(width 0.1)
				(type default)
			)
			(layer "B.Fab")
		)
		(fp_line
			(start 0.2794 -0.1016)
			(end 0.2794 0.9906)
			(stroke
				(width 0.1)
				(type default)
			)
			(layer "B.Fab")
		)
		(pad "1" smd rect
			(at 0 0 90)
			(size 0.508 0.508)
			(layers "B.Cu" "B.Mask" "B.Paste")
			(net "FM_CPU0_PROCHOT_LVT3_K_N")
		)
		(pad "2" smd rect
			(at 0 0.889 90)
			(size 0.508 0.508)
			(layers "B.Cu" "B.Mask" "B.Paste")
			(net "H_CPU0_PROCHOT_G_PCH_N")
		)
		(zone
			(layer "B.Cu")
			(hatch none 0.5)
			(connect_pads
				(clearance 0)
			)
			(min_thickness 0.25)
			(keepout
				(tracks not_allowed)
				(vias allowed)
				(pads allowed)
				(copperpour not_allowed)
				(footprints allowed)
			)
			(placement
				(enabled no)
				(sheetname "")
			)
			(fill
				(thermal_gap 0.5)
				(thermal_bridge_width 0.5)
				(island_removal_mode 0)
			)
			(polygon
				(pts
					(xy 360.809794 -45.353986) (xy 360.809794 -45.861986) (xy 361.190794 -45.861986) (xy 361.190794 -45.353986)
				)
			)
		)
		(zone
			(layer "B.Cu")
			(hatch none 0.5)
			(connect_pads
				(clearance 0)
			)
			(min_thickness 0.25)
			(keepout
				(tracks allowed)
				(vias not_allowed)
				(pads allowed)
				(copperpour not_allowed)
				(footprints allowed)
			)
			(placement
				(enabled no)
				(sheetname "")
			)
			(fill
				(thermal_gap 0.5)
				(thermal_bridge_width 0.5)
				(island_removal_mode 0)
			)
			(polygon
				(pts
					(xy 361.190794 -45.353986) (xy 361.190794 -45.861986) (xy 360.809794 -45.861986) (xy 360.809794 -45.353986)
				)
			)
		)
	)
	(footprint ""
		(layer "B.Cu")
		(at 352.96729 -77.915516 180)
		(property "Reference" "C3P30"
			(at 0 0 0)
			(layer "B.SilkS")
			(hide yes)
			(effects
				(font
					(size 1.27 1.27)
				)
				(justify mirror)
			)
		)
		(property "Value" ""
			(at 0 0 0)
			(layer "B.Fab")
			(effects
				(font
					(size 1.27 1.27)
				)
				(justify mirror)
			)
		)
		(duplicate_pad_numbers_are_jumpers no)
		(fp_poly
			(pts
				(xy -0.3048 -0.1016) (xy -0.3048 0.9906) (xy 0.3048 0.9906) (xy 0.3048 -0.1016)
			)
			(stroke
				(width 0)
				(type default)
			)
			(fill no)
			(layer "B.CrtYd")
		)
		(fp_line
			(start 0.3048 0.9906)
			(end -0.3048 0.9906)
			(stroke
				(width 0.1)
				(type default)
			)
			(layer "B.Fab")
		)
		(fp_line
			(start 0.3048 -0.1016)
			(end 0.3048 0.9906)
			(stroke
				(width 0.1)
				(type default)
			)
			(layer "B.Fab")
		)
		(fp_line
			(start -0.3048 0.9906)
			(end -0.3048 -0.1016)
			(stroke
				(width 0.1)
				(type default)
			)
			(layer "B.Fab")
		)
		(fp_line
			(start -0.3048 -0.1016)
			(end 0.3048 -0.1016)
			(stroke
				(width 0.1)
				(type default)
			)
			(layer "B.Fab")
		)
		(pad "1" smd rect
			(at 0 0)
			(size 0.508 0.508)
			(layers "B.Cu" "B.Mask" "B.Paste")
			(net "P3E_CPU0_PE1_SS_TXP<5>")
		)
		(pad "2" smd rect
			(at 0 0.889)
			(size 0.508 0.508)
			(layers "B.Cu" "B.Mask" "B.Paste")
			(net "P3E_CPU0_PE1_PCH_TXP<5>")
		)
		(zone
			(layer "B.Cu")
			(hatch none 0.5)
			(connect_pads
				(clearance 0)
			)
			(min_thickness 0.25)
			(keepout
				(tracks not_allowed)
				(vias allowed)
				(pads allowed)
				(copperpour not_allowed)
				(footprints allowed)
			)
			(placement
				(enabled no)
				(sheetname "")
			)
			(fill
				(thermal_gap 0.5)
				(thermal_bridge_width 0.5)
				(island_removal_mode 0)
			)
			(polygon
				(pts
					(xy 352.71329 -78.550516) (xy 353.22129 -78.550516) (xy 353.22129 -78.169516) (xy 352.71329 -78.169516)
				)
			)
		)
		(zone
			(layer "B.Cu")
			(hatch none 0.5)
			(connect_pads
				(clearance 0)
			)
			(min_thickness 0.25)
			(keepout
				(tracks allowed)
				(vias not_allowed)
				(pads allowed)
				(copperpour not_allowed)
				(footprints allowed)
			)
			(placement
				(enabled no)
				(sheetname "")
			)
			(fill
				(thermal_gap 0.5)
				(thermal_bridge_width 0.5)
				(island_removal_mode 0)
			)
			(polygon
				(pts
					(xy 352.71329 -78.169516) (xy 353.22129 -78.169516) (xy 353.22129 -78.550516) (xy 352.71329 -78.550516)
				)
			)
		)
	)
)
